#ISCELL
  mstr_misc dns *
  *
#ISCELL
  pure_quanta quanta_title_block_c *
  *
#ISCELL
  standard offpage *
  page143_i1
#ISCELL
  logical_power universal_gnd *
  page143_i10
#CELL
  pure_quanta q_res *
  page143_i100
#CELL
  pure_quanta q_res *
  page143_i101
#ISCELL
  standard offpage *
  page143_i102
#ISCELL
  logical_power universal_power *
  page143_i103
#ISCELL
  logical_power universal_gnd *
  page143_i104
#CELL
  pure_quanta q_cap *
  page143_i105
#ISCELL
  logical_power universal_gnd *
  page143_i106
#CELL
  pure_quanta mosfet_nch_dual *
  page143_i107
#ISCELL
  logical_power universal_power *
  page143_i108
#ISCELL
  logical_power universal_gnd *
  page143_i109
#CELL
  pure_quanta mosfet_nch_dual *
  page143_i11
#ISCELL
  logical_power universal_power *
  page143_i110
#ISCELL
  standard offpage *
  page143_i112
#CELL
  pure_quanta q_res *
  page143_i113
#ISCELL
  logical_power universal_gnd *
  page143_i114
#CELL
  pure_quanta q_res *
  page143_i116
#ISCELL
  standard offpage *
  page143_i117
#CELL
  pure_quanta q_cap *
  page143_i118
#ISCELL
  logical_power universal_gnd *
  page143_i119
#ISCELL
  logical_power universal_power *
  page143_i12
#ISCELL
  logical_power universal_power *
  page143_i120
#CELL
  pure_quanta mosfet_nch_dual *
  page143_i121
#ISCELL
  logical_power universal_gnd *
  page143_i122
#ISCELL
  logical_power universal_power *
  page143_i123
#CELL
  pure_quanta q_res *
  page143_i124
#ISCELL
  logical_power universal_gnd *
  page143_i125
#CELL
  pure_quanta mosfet_nch_dual *
  page143_i126
#ISCELL
  logical_power universal_power *
  page143_i127
#CELL
  pure_quanta q_res *
  page143_i129
#CELL
  pure_quanta q_res *
  page143_i13
#ISCELL
  logical_power universal_gnd *
  page143_i130
#ISCELL
  standard offpage *
  page143_i131
#CELL
  pure_quanta q_res *
  page143_i132
#CELL
  pure_quanta q_res *
  page143_i136
#CELL
  pure_quanta q_res *
  page143_i137
#CELL
  pure_quanta q_res *
  page143_i138
#CELL
  pure_quanta q_res *
  page143_i139
#CELL
  pure_quanta q_res *
  page143_i14
#CELL
  pure_quanta q_res *
  page143_i140
#CELL
  pure_quanta q_res *
  page143_i141
#CELL
  pure_quanta q_res *
  page143_i142
#CELL
  pure_quanta q_res *
  page143_i143
#CELL
  pure_quanta q_res *
  page143_i144
#CELL
  pure_quanta q_res *
  page143_i145
#ISCELL
  standard offpage *
  page143_i15
#ISCELL
  logical_power universal_gnd *
  page143_i16
#CELL
  pure_quanta mosfet_nch_dual *
  page143_i19
#CELL
  pure_quanta q_cap *
  page143_i2
#ISCELL
  logical_power universal_power *
  page143_i20
#CELL
  pure_quanta q_res *
  page143_i21
#ISCELL
  standard offpage *
  page143_i22
#CELL
  pure_quanta q_cap *
  page143_i23
#ISCELL
  logical_power universal_gnd *
  page143_i24
#ISCELL
  logical_power universal_gnd *
  page143_i25
#ISCELL
  logical_power universal_power *
  page143_i26
#CELL
  pure_quanta q_res *
  page143_i27
#ISCELL
  logical_power universal_gnd *
  page143_i28
#CELL
  pure_quanta mosfet_nch_dual *
  page143_i29
#ISCELL
  logical_power universal_gnd *
  page143_i3
#ISCELL
  logical_power universal_power *
  page143_i30
#CELL
  pure_quanta q_res *
  page143_i31
#CELL
  pure_quanta q_res *
  page143_i32
#ISCELL
  standard offpage *
  page143_i33
#ISCELL
  logical_power universal_gnd *
  page143_i34
#CELL
  pure_quanta mosfet_nch_dual *
  page143_i35
#CELL
  pure_quanta q_res *
  page143_i36
#ISCELL
  logical_power universal_power *
  page143_i37
#ISCELL
  logical_power universal_power *
  page143_i38
#ISCELL
  standard offpage *
  page143_i39
#ISCELL
  logical_power universal_power *
  page143_i4
#CELL
  pure_quanta q_cap *
  page143_i40
#ISCELL
  logical_power universal_gnd *
  page143_i41
#ISCELL
  logical_power universal_gnd *
  page143_i42
#CELL
  pure_quanta q_res *
  page143_i43
#CELL
  pure_quanta mosfet_nch_dual *
  page143_i44
#ISCELL
  logical_power universal_gnd *
  page143_i45
#ISCELL
  logical_power universal_power *
  page143_i46
#ISCELL
  standard offpage *
  page143_i48
#CELL
  pure_quanta q_res *
  page143_i49
#CELL
  pure_quanta q_res *
  page143_i5
#ISCELL
  logical_power universal_gnd *
  page143_i50
#ISCELL
  logical_power universal_power *
  page143_i51
#CELL
  pure_quanta q_res *
  page143_i52
#ISCELL
  standard offpage *
  page143_i53
#ISCELL
  standard offpage *
  page143_i54
#CELL
  pure_quanta q_cap *
  page143_i55
#ISCELL
  logical_power universal_gnd *
  page143_i56
#CELL
  pure_quanta q_cap *
  page143_i57
#ISCELL
  logical_power universal_gnd *
  page143_i58
#ISCELL
  logical_power universal_power *
  page143_i59
#CELL
  pure_quanta mosfet_nch_dual *
  page143_i6
#CELL
  pure_quanta q_res *
  page143_i60
#ISCELL
  standard offpage *
  page143_i61
#ISCELL
  logical_power universal_power *
  page143_i62
#ISCELL
  logical_power universal_gnd *
  page143_i63
#CELL
  pure_quanta q_res *
  page143_i64
#ISCELL
  logical_power universal_gnd *
  page143_i65
#CELL
  pure_quanta q_cap *
  page143_i66
#ISCELL
  logical_power universal_gnd *
  page143_i67
#ISCELL
  logical_power universal_gnd *
  page143_i68
#ISCELL
  logical_power universal_power *
  page143_i69
#ISCELL
  logical_power universal_gnd *
  page143_i7
#CELL
  pure_quanta mosfet_nch_dual *
  page143_i70
#CELL
  pure_quanta mosfet_nch_dual *
  page143_i71
#CELL
  pure_quanta q_res *
  page143_i72
#ISCELL
  logical_power universal_gnd *
  page143_i73
#CELL
  pure_quanta mosfet_nch_dual *
  page143_i74
#ISCELL
  logical_power universal_power *
  page143_i75
#CELL
  pure_quanta q_res *
  page143_i76
#CELL
  pure_quanta mosfet_nch_dual *
  page143_i77
#CELL
  pure_quanta mosfet_nch_dual *
  page143_i78
#ISCELL
  logical_power universal_gnd *
  page143_i79
#ISCELL
  logical_power universal_power *
  page143_i8
#ISCELL
  logical_power universal_power *
  page143_i80
#CELL
  pure_quanta q_res *
  page143_i81
#ISCELL
  logical_power universal_gnd *
  page143_i82
#CELL
  pure_quanta mosfet_nch_dual *
  page143_i83
#ISCELL
  logical_power universal_power *
  page143_i84
#CELL
  pure_quanta q_res *
  page143_i85
#CELL
  pure_quanta q_res *
  page143_i86
#ISCELL
  standard offpage *
  page143_i87
#ISCELL
  logical_power universal_gnd *
  page143_i88
#ISCELL
  logical_power universal_power *
  page143_i89
#CELL
  pure_quanta q_res *
  page143_i9
#CELL
  pure_quanta q_res *
  page143_i91
#ISCELL
  logical_power universal_gnd *
  page143_i92
#ISCELL
  logical_power universal_power *
  page143_i93
#ISCELL
  standard offpage *
  page143_i94
#CELL
  pure_quanta q_res *
  page143_i95
#CELL
  pure_quanta q_res *
  page143_i96
#ISCELL
  logical_power universal_gnd *
  page143_i97
#ISCELL
  standard offpage *
  page143_i98
#CELL
  pure_quanta mosfet_nch_dual *
  page143_i99
